#ISCELL
  cls sheet_a1 *
  *
#ISCELL
  cls gnd_sg *
  page517_i1
#CELL
  passive resistor *
  page517_i10
#CELL
  passive resistor *
  page517_i11
#CELL
  passive capacitor *
  page517_i12
#CELL
  passive resistor *
  page517_i13
#CELL
  passive capacitor *
  page517_i14
#CELL
  passive capacitor *
  page517_i15
#CELL
  passive capacitor *
  page517_i16
#CELL
  passive capacitor *
  page517_i17
#CELL
  passive resistor *
  page517_i18
#CELL
  passive capacitor *
  page517_i19
#CELL
  passive capacitor *
  page517_i2
#ISCELL
  cls gnd_sg *
  page517_i20
#CELL
  passive capacitor *
  page517_i21
#ISCELL
  cls vcc *
  page517_i22
#ISCELL
  cls gnd_sg *
  page517_i23
#CELL
  mech solder_preform *
  page517_i24
#CELL
  passive resistor *
  page517_i25
#CELL
  passive resistor *
  page517_i26
#CELL
  passive capacitor *
  page517_i27
#CELL
  passive inductor_2 *
  page517_i28
#CELL
  passive capacitor *
  page517_i29
#CELL
  passive resistor *
  page517_i3
#CELL
  passive capacitor *
  page517_i30
#CELL
  passive resistor *
  page517_i31
#CELL
  passive resistor *
  page517_i32
#CELL
  passive resistor *
  page517_i33
#ISCELL
  cls gnd_sg *
  page517_i34
#ISCELL
  cls gnd_sg *
  page517_i35
#CELL
  passive capacitor *
  page517_i36
#CELL
  passive capacitor *
  page517_i37
#CELL
  passive capacitor *
  page517_i38
#ISCELL
  cls vcc *
  page517_i39
#CELL
  passive capacitor *
  page517_i40
#CELL
  passive resistor *
  page517_i41
#CELL
  stdlogic tps54824rnvr_vqfn18 *
  page517_i42
#CELL
  passive resistor *
  page517_i47
#ISCELL
  cls offpage_out *
  page517_i48
#ISCELL
  cls vcc *
  page517_i49
#ISCELL
  cls gnd_sg *
  page517_i5
#CELL
  passive capacitor *
  page517_i51
#ISCELL
  cls offpage_in *
  page517_i52
#CELL
  passive capacitor *
  page517_i6
#CELL
  passive ferritebead *
  page517_i7
#ISCELL
  cls gnd_sg *
  page517_i8
#CELL
  passive capacitor *
  page517_i9
